# T6G (Grand Teton) — schematic netlist excerpt (pin names and nets, part order shuffled) for the footprints in the layout excerpt that follows; sources: Cadence DE-HDL packaged netlist, KiCad conversion of 04192023_DAF0TMB3IC0_F0TG_MB_C_brd_V02_OCP.brd

C2029  Q_CAP  15PF 50V 5% C0G  pkg 0402  page 234 : A = USB_HUB_XTAL_IN ; B = GND
PC393  Q_CAPP  270UF 16V 20% OSCON  pkg SMLF  page 218 : A = SW_P12V_AUX_PVDDCR_CPU1_P1_FLT ; B = GND
C831  Q_CAP_DIFFBUS  DIFF BUS_0.22UF 6.3V 20% X6S  pkg C0201  page 65 : \1\ = P5E_CPU1_P0_TX_C_DP<3> ; \2\ = P5E_CPU1_P0_TX_DP<3>
R668  Q_RES  33.2 1% CHIP  pkg 0201LF  page 278 : A = SMB_RT_CPU0_P0_ROM_R_SCL ; B = SMB_RT_CPU0_P0_ROM_SCL

(kicad_pcb
	(version 20260206)
	(generator "pcbnew")
	(generator_version "10.0")
	(general
		(thickness 1.6)
		(legacy_teardrops no)
	)
	(paper "A4")
	(title_block
		(title "04192023_DAF0TMB3IC0_F0TG_MB_C_brd_V02_OCP.brd")
		(comment 1 "Grand Teton / footprints 16-19 of 8354")
	)
	(layers
		(0 "F.Cu" signal "TOP")
		(4 "In1.Cu" signal "GND")
		(6 "In2.Cu" signal "IN1")
		(8 "In3.Cu" signal "GND1")
		(10 "In4.Cu" signal "IN2")
		(12 "In5.Cu" signal "GND2")
		(14 "In6.Cu" signal "IN3")
		(16 "In7.Cu" signal "GND3")
		(18 "In8.Cu" signal "VCC")
		(20 "In9.Cu" signal "VCC1")
		(22 "In10.Cu" signal "GND4")
		(24 "In11.Cu" signal "IN4")
		(26 "In12.Cu" signal "GND5")
		(28 "In13.Cu" signal "IN5")
		(30 "In14.Cu" signal "GND6")
		(32 "In15.Cu" signal "IN6")
		(34 "In16.Cu" signal "GND7")
		(2 "B.Cu" signal "BOTTOM")
		(9 "F.Adhes" user "F.Adhesive")
		(11 "B.Adhes" user "B.Adhesive")
		(13 "F.Paste" user "Package Geometry/Pastemask Top")
		(15 "B.Paste" user "Package Geometry/Pastemask Bottom")
		(5 "F.SilkS" user "Ref Des/Silkscreen Top")
		(7 "B.SilkS" user "Ref Des/Silkscreen Bottom")
		(1 "F.Mask" user "Board Geometry/Soldermask Top")
		(3 "B.Mask" user "Board Geometry/Soldermask Bottom")
		(17 "Dwgs.User" user "User.Drawings")
		(19 "Cmts.User" user "User.Comments")
		(21 "Eco1.User" user "User.Eco1")
		(23 "Eco2.User" user "User.Eco2")
		(25 "Edge.Cuts" user "Board Geometry/Outline")
		(27 "Margin" user)
		(31 "F.CrtYd" user "Package Geometry/Place Bound Top")
		(29 "B.CrtYd" user "Package Geometry/Place Bound Bottom")
		(35 "F.Fab" user "Ref Des/Assembly Top")
		(33 "B.Fab" user "Ref Des/Assembly Bottom")
	)
	(footprint ""
		(layer "F.Cu")
		(at 9.277096 -100.017834 90)
		(property "Reference" "C2029"
			(at 0 0 90)
			(layer "F.SilkS")
			(hide yes)
			(effects
				(font
					(size 1.27 1.27)
				)
			)
		)
		(property "Value" ""
			(at 0 0 90)
			(layer "F.Fab")
			(effects
				(font
					(size 1.27 1.27)
				)
			)
		)
		(duplicate_pad_numbers_are_jumpers no)
		(fp_line
			(start 0.7874 -0.4064)
			(end 0.7874 0.4064)
			(stroke
				(width 0.1524)
				(type default)
			)
			(layer "F.SilkS")
		)
		(fp_line
			(start -0.7874 -0.4064)
			(end 0.7874 -0.4064)
			(stroke
				(width 0.1524)
				(type default)
			)
			(layer "F.SilkS")
		)
		(fp_line
			(start 0.7874 0.4064)
			(end -0.7874 0.4064)
			(stroke
				(width 0.1524)
				(type default)
			)
			(layer "F.SilkS")
		)
		(fp_line
			(start -0.7874 0.4064)
			(end -0.7874 -0.4064)
			(stroke
				(width 0.1524)
				(type default)
			)
			(layer "F.SilkS")
		)
		(fp_line
			(start -0.12065 -0.305054)
			(end -0.12065 -0.2794)
			(stroke
				(width 0.1)
				(type default)
			)
			(layer "F.Fab")
		)
		(fp_line
			(start -0.67945 -0.305054)
			(end -0.12065 -0.305054)
			(stroke
				(width 0.1)
				(type default)
			)
			(layer "F.Fab")
		)
		(fp_line
			(start 0.67945 -0.3048)
			(end 0.67945 0.3048)
			(stroke
				(width 0.1)
				(type default)
			)
			(layer "F.Fab")
		)
		(fp_line
			(start 0.12065 -0.3048)
			(end 0.67945 -0.3048)
			(stroke
				(width 0.1)
				(type default)
			)
			(layer "F.Fab")
		)
		(fp_line
			(start 0.12065 -0.2794)
			(end 0.12065 -0.3048)
			(stroke
				(width 0.1)
				(type default)
			)
			(layer "F.Fab")
		)
		(fp_line
			(start -0.12065 -0.2794)
			(end 0.12065 -0.2794)
			(stroke
				(width 0.1)
				(type default)
			)
			(layer "F.Fab")
		)
		(fp_line
			(start 0.120396 0.2794)
			(end -0.12065 0.2794)
			(stroke
				(width 0.1)
				(type default)
			)
			(layer "F.Fab")
		)
		(fp_line
			(start -0.12065 0.2794)
			(end -0.12065 0.3048)
			(stroke
				(width 0.1)
				(type default)
			)
			(layer "F.Fab")
		)
		(fp_line
			(start 0.67945 0.3048)
			(end 0.120396 0.3048)
			(stroke
				(width 0.1)
				(type default)
			)
			(layer "F.Fab")
		)
		(fp_line
			(start 0.120396 0.3048)
			(end 0.120396 0.2794)
			(stroke
				(width 0.1)
				(type default)
			)
			(layer "F.Fab")
		)
		(fp_line
			(start -0.12065 0.3048)
			(end -0.67945 0.3048)
			(stroke
				(width 0.1)
				(type default)
			)
			(layer "F.Fab")
		)
		(fp_line
			(start -0.67945 0.3048)
			(end -0.67945 -0.305054)
			(stroke
				(width 0.1)
				(type default)
			)
			(layer "F.Fab")
		)
		(pad "1" smd circle
			(at -0.40005 0 90)
			(size 0 0)
			(layers "F.Cu" "F.Mask" "F.Paste")
			(net "USB_HUB_XTAL_IN")
		)
		(pad "2" smd circle
			(at 0.40005 0 90)
			(size 0 0)
			(layers "F.Cu" "F.Mask" "F.Paste")
			(net "GND")
		)
	)
	(footprint ""
		(layer "F.Cu")
		(at 294.560752 -422.173908 90)
		(property "Reference" "R668"
			(at 0 0 90)
			(layer "F.SilkS")
			(hide yes)
			(effects
				(font
					(size 1.27 1.27)
				)
			)
		)
		(property "Value" ""
			(at 0 0 90)
			(layer "F.Fab")
			(effects
				(font
					(size 1.27 1.27)
				)
			)
		)
		(duplicate_pad_numbers_are_jumpers no)
		(fp_line
			(start 0.32512 -0.175006)
			(end 0.32512 0.175006)
			(stroke
				(width 0.1)
				(type default)
			)
			(layer "F.Fab")
		)
		(fp_line
			(start -0.32512 -0.175006)
			(end 0.32512 -0.175006)
			(stroke
				(width 0.1)
				(type default)
			)
			(layer "F.Fab")
		)
		(fp_line
			(start 0.32512 0.175006)
			(end -0.32512 0.175006)
			(stroke
				(width 0.1)
				(type default)
			)
			(layer "F.Fab")
		)
		(fp_line
			(start -0.32512 0.175006)
			(end -0.32512 -0.175006)
			(stroke
				(width 0.1)
				(type default)
			)
			(layer "F.Fab")
		)
		(pad "1" smd rect
			(at -0.2667 0 90)
			(size 0.3048 0.381)
			(layers "F.Cu" "F.Mask" "F.Paste")
			(net "SMB_RT_CPU0_P0_ROM_R_SCL")
		)
		(pad "2" smd rect
			(at 0.2667 0 270)
			(size 0.3048 0.381)
			(layers "F.Cu" "F.Mask" "F.Paste")
			(net "SMB_RT_CPU0_P0_ROM_SCL")
		)
	)
	(footprint ""
		(layer "F.Cu")
		(at 44.691554 -370.57203 -90)
		(property "Reference" "C831"
			(at 0 0 270)
			(layer "F.SilkS")
			(hide yes)
			(effects
				(font
					(size 1.27 1.27)
				)
			)
		)
		(property "Value" ""
			(at 0 0 270)
			(layer "F.Fab")
			(effects
				(font
					(size 1.27 1.27)
				)
			)
		)
		(duplicate_pad_numbers_are_jumpers no)
		(fp_line
			(start -0.299974 0.150114)
			(end -0.299974 -0.150114)
			(stroke
				(width 0.1)
				(type default)
			)
			(layer "F.Fab")
		)
		(fp_line
			(start 0.299974 0.150114)
			(end -0.299974 0.150114)
			(stroke
				(width 0.1)
				(type default)
			)
			(layer "F.Fab")
		)
		(fp_line
			(start -0.299974 -0.150114)
			(end 0.299974 -0.150114)
			(stroke
				(width 0.1)
				(type default)
			)
			(layer "F.Fab")
		)
		(fp_line
			(start 0.299974 -0.150114)
			(end 0.299974 0.150114)
			(stroke
				(width 0.1)
				(type default)
			)
			(layer "F.Fab")
		)
		(pad "1" smd rect
			(at -0.2667 0 270)
			(size 0.3048 0.381)
			(layers "F.Cu" "F.Mask" "F.Paste")
			(net "P5E_CPU1_P0_TX_C_DP<3>")
		)
		(pad "2" smd rect
			(at 0.2667 0 270)
			(size 0.3048 0.381)
			(layers "F.Cu" "F.Mask" "F.Paste")
			(net "P5E_CPU1_P0_TX_DP<3>")
		)
	)
	(footprint ""
		(layer "F.Cu")
		(at 76.211176 -355.008434 90)
		(property "Reference" "PC393"
			(at -5.277104 -1.789176 0)
			(unlocked yes)
			(layer "F.SilkS")
			(effects
				(font
					(size 0.7874 0.5842)
					(thickness 0.1524)
				)
				(justify left)
			)
		)
		(property "Value" ""
			(at 0 0 90)
			(layer "F.Fab")
			(effects
				(font
					(size 1.27 1.27)
				)
			)
		)
		(duplicate_pad_numbers_are_jumpers no)
		(fp_line
			(start 3.400044 -3.400044)
			(end -2.146046 -3.400044)
			(stroke
				(width 0.1524)
				(type default)
			)
			(layer "F.SilkS")
		)
		(fp_line
			(start -2.146046 -3.400044)
			(end -3.400044 -2.146046)
			(stroke
				(width 0.1524)
				(type default)
			)
			(layer "F.SilkS")
		)
		(fp_line
			(start -3.400044 -2.146046)
			(end -3.400044 -0.9398)
			(stroke
				(width 0.1524)
				(type default)
			)
			(layer "F.SilkS")
		)
		(fp_line
			(start 3.400044 -0.9398)
			(end 3.400044 -3.400044)
			(stroke
				(width 0.1524)
				(type default)
			)
			(layer "F.SilkS")
		)
		(fp_line
			(start 3.400044 0.9398)
			(end 3.400044 3.400044)
			(stroke
				(width 0.1524)
				(type default)
			)
			(layer "F.SilkS")
		)
		(fp_line
			(start -3.400044 2.146046)
			(end -3.400044 0.9398)
			(stroke
				(width 0.1524)
				(type default)
			)
			(layer "F.SilkS")
		)
		(fp_line
			(start 3.400044 3.400044)
			(end -2.146046 3.400044)
			(stroke
				(width 0.1524)
				(type default)
			)
			(layer "F.SilkS")
		)
		(fp_line
			(start -2.146046 3.400044)
			(end -3.400044 2.146046)
			(stroke
				(width 0.1524)
				(type default)
			)
			(layer "F.SilkS")
		)
		(fp_line
			(start 3.400044 -3.400044)
			(end -3.400044 -3.400044)
			(stroke
				(width 0.1)
				(type default)
			)
			(layer "F.Fab")
		)
		(fp_line
			(start -3.400044 -3.400044)
			(end -3.400044 3.400044)
			(stroke
				(width 0.1)
				(type default)
			)
			(layer "F.Fab")
		)
		(fp_line
			(start 3.400044 3.400044)
			(end 3.400044 -3.400044)
			(stroke
				(width 0.1)
				(type default)
			)
			(layer "F.Fab")
		)
		(fp_line
			(start -3.400044 3.400044)
			(end 3.400044 3.400044)
			(stroke
				(width 0.1)
				(type default)
			)
			(layer "F.Fab")
		)
		(pad "1" smd rect
			(at -2.70002 0)
			(size 1.6002 3.5052)
			(layers "F.Cu" "F.Mask" "F.Paste")
			(net "SW_P12V_AUX_PVDDCR_CPU1_P1_FLT")
		)
		(pad "2" smd rect
			(at 2.70002 0)
			(size 1.6002 3.5052)
			(layers "F.Cu" "F.Mask" "F.Paste")
			(net "GND")
		)
	)
)
